# BASEBOARD_FAB2 (Tioga Pass) — schematic netlist excerpt (pin names and nets, part order shuffled) for the footprints in the layout excerpt that follows; sources: Cadence DE-HDL packaged netlist, KiCad conversion of Wiwynn_Tioga_Pass_MB.brd

U6W4  TTL1G126_A  74HC1G126 IC  pkg SOT  page 176
  OE  = DEBUG_CARD2_PRSNT
  A  = SPA_MID_DBG2_RX
  Y  = SPA_MID_DBG2_RX_BUF

R25W176  RES  1.00K 1% CHIP  pkg 0402  page 255 : A = PD_GTL2014_6_B2 ; B = GND
R3N31  RES  3.16K 1% CHIP  pkg 0402  page 211 : A = VR_PVCCIO_CPU0_XADDR1 ; B = GND

(kicad_pcb
	(version 20260206)
	(generator "pcbnew")
	(generator_version "10.0")
	(general
		(thickness 1.6)
		(legacy_teardrops no)
	)
	(paper "A4")
	(title_block
		(title "Wiwynn_Tioga_Pass_MB.brd")
		(comment 1 "Tioga Pass / footprints 3405-3407 of 4770")
	)
	(layers
		(0 "F.Cu" signal "TOP")
		(4 "In1.Cu" signal "L2GND")
		(6 "In2.Cu" signal "L3")
		(8 "In3.Cu" signal "L4GND")
		(10 "In4.Cu" signal "L5")
		(12 "In5.Cu" signal "L6GND")
		(14 "In6.Cu" signal "L7VCC")
		(16 "In7.Cu" signal "L8VCC")
		(18 "In8.Cu" signal "L9GND")
		(20 "In9.Cu" signal "L10")
		(22 "In10.Cu" signal "L11GND")
		(24 "In11.Cu" signal "L12")
		(26 "In12.Cu" signal "L13GND")
		(2 "B.Cu" signal "BOTTOM")
		(9 "F.Adhes" user "F.Adhesive")
		(11 "B.Adhes" user "B.Adhesive")
		(13 "F.Paste" user "Package Geometry/Pastemask Top")
		(15 "B.Paste" user "Package Geometry/Pastemask Bottom")
		(5 "F.SilkS" user "Ref Des/Silkscreen Top")
		(7 "B.SilkS" user "Ref Des/Silkscreen Bottom")
		(1 "F.Mask" user "Board Geometry/Soldermask Top")
		(3 "B.Mask" user "Board Geometry/Soldermask Bottom")
		(17 "Dwgs.User" user "User.Drawings")
		(19 "Cmts.User" user "User.Comments")
		(21 "Eco1.User" user "User.Eco1")
		(23 "Eco2.User" user "User.Eco2")
		(25 "Edge.Cuts" user "Board Geometry/Outline")
		(27 "Margin" user)
		(31 "F.CrtYd" user "Package Geometry/Place Bound Top")
		(29 "B.CrtYd" user "Package Geometry/Place Bound Bottom")
		(35 "F.Fab" user "Ref Des/Assembly Top")
		(33 "B.Fab" user "Ref Des/Assembly Bottom")
	)
	(footprint ""
		(layer "B.Cu")
		(at 450.215 -150.1394 -90)
		(property "Reference" "R25W176"
			(at 0.8382 -0.67818 270)
			(unlocked yes)
			(layer "B.SilkS")
			(effects
				(font
					(size 0.4064 0.254)
					(thickness 0.1524)
				)
				(justify left mirror)
			)
		)
		(property "Value" ""
			(at 0 0 90)
			(layer "B.Fab")
			(effects
				(font
					(size 1.27 1.27)
				)
				(justify mirror)
			)
		)
		(duplicate_pad_numbers_are_jumpers no)
		(fp_poly
			(pts
				(xy 0.2794 -0.1016) (xy -0.2794 -0.1016) (xy -0.2794 0.9906) (xy 0.2794 0.9906)
			)
			(stroke
				(width 0)
				(type default)
			)
			(fill no)
			(layer "B.CrtYd")
		)
		(fp_line
			(start -0.2794 0.9906)
			(end -0.2794 -0.1016)
			(stroke
				(width 0.1)
				(type default)
			)
			(layer "B.Fab")
		)
		(fp_line
			(start 0.2794 0.9906)
			(end -0.2794 0.9906)
			(stroke
				(width 0.1)
				(type default)
			)
			(layer "B.Fab")
		)
		(fp_line
			(start -0.2794 -0.1016)
			(end 0.2794 -0.1016)
			(stroke
				(width 0.1)
				(type default)
			)
			(layer "B.Fab")
		)
		(fp_line
			(start 0.2794 -0.1016)
			(end 0.2794 0.9906)
			(stroke
				(width 0.1)
				(type default)
			)
			(layer "B.Fab")
		)
		(pad "1" smd rect
			(at 0 0 90)
			(size 0.508 0.508)
			(layers "B.Cu" "B.Mask" "B.Paste")
			(net "PD_GTL2014_6_B2")
		)
		(pad "2" smd rect
			(at 0 0.889 90)
			(size 0.508 0.508)
			(layers "B.Cu" "B.Mask" "B.Paste")
			(net "GND")
		)
		(zone
			(layer "B.Cu")
			(hatch none 0.5)
			(connect_pads
				(clearance 0)
			)
			(min_thickness 0.25)
			(keepout
				(tracks not_allowed)
				(vias allowed)
				(pads allowed)
				(copperpour not_allowed)
				(footprints allowed)
			)
			(placement
				(enabled no)
				(sheetname "")
			)
			(fill
				(thermal_gap 0.5)
				(thermal_bridge_width 0.5)
				(island_removal_mode 0)
			)
			(polygon
				(pts
					(xy 449.58 -149.8854) (xy 449.58 -150.3934) (xy 449.961 -150.3934) (xy 449.961 -149.8854)
				)
			)
		)
		(zone
			(layer "B.Cu")
			(hatch none 0.5)
			(connect_pads
				(clearance 0)
			)
			(min_thickness 0.25)
			(keepout
				(tracks allowed)
				(vias not_allowed)
				(pads allowed)
				(copperpour not_allowed)
				(footprints allowed)
			)
			(placement
				(enabled no)
				(sheetname "")
			)
			(fill
				(thermal_gap 0.5)
				(thermal_bridge_width 0.5)
				(island_removal_mode 0)
			)
			(polygon
				(pts
					(xy 449.961 -149.8854) (xy 449.961 -150.3934) (xy 449.58 -150.3934) (xy 449.58 -149.8854)
				)
			)
		)
	)
	(footprint ""
		(layer "B.Cu")
		(at 492.3536 -133.223 90)
		(property "Reference" "U6W4"
			(at 0.14986 2.621788 90)
			(unlocked yes)
			(layer "B.SilkS")
			(effects
				(font
					(size 1.27 0.964946)
					(thickness 0.000001)
				)
				(justify left mirror)
			)
		)
		(property "Value" ""
			(at 0 0 90)
			(layer "B.Fab")
			(effects
				(font
					(size 1.27 1.27)
				)
				(justify mirror)
			)
		)
		(duplicate_pad_numbers_are_jumpers no)
		(fp_circle
			(center 0.4699 -0.8382)
			(end 0.4699 -0.7112)
			(stroke
				(width 0.254)
				(type default)
			)
			(fill no)
			(layer "B.SilkS")
		)
		(fp_poly
			(pts
				(xy -0.21463 -0.450088) (xy -1.56337 -0.450088) (xy -1.56337 1.75006) (xy -0.21463 1.75006)
			)
			(stroke
				(width 0)
				(type default)
			)
			(fill no)
			(layer "B.CrtYd")
		)
		(fp_line
			(start -0.21463 -0.450088)
			(end -1.56337 -0.450088)
			(stroke
				(width 0.1)
				(type default)
			)
			(layer "B.Fab")
		)
		(fp_line
			(start -1.56337 -0.450088)
			(end -1.56337 1.75006)
			(stroke
				(width 0.1)
				(type default)
			)
			(layer "B.Fab")
		)
		(fp_line
			(start -0.21463 1.75006)
			(end -0.21463 -0.450088)
			(stroke
				(width 0.1)
				(type default)
			)
			(layer "B.Fab")
		)
		(fp_line
			(start -1.56337 1.75006)
			(end -0.21463 1.75006)
			(stroke
				(width 0.1)
				(type default)
			)
			(layer "B.Fab")
		)
		(fp_circle
			(center 0.4699 -0.8382)
			(end 0.4699 -0.7112)
			(stroke
				(width 0.254)
				(type default)
			)
			(fill no)
			(layer "B.Fab")
		)
		(pad "1" smd rect
			(at 0 0 270)
			(size 1.016 0.381)
			(layers "B.Cu" "B.Mask" "B.Paste")
			(net "DEBUG_CARD2_PRSNT")
		)
		(pad "2" smd rect
			(at 0 0.649986 270)
			(size 1.016 0.381)
			(layers "B.Cu" "B.Mask" "B.Paste")
			(net "SPA_MID_DBG2_RX")
		)
		(pad "3" smd rect
			(at 0 1.299972 270)
			(size 1.016 0.381)
			(layers "B.Cu" "B.Mask" "B.Paste")
			(net "GND")
		)
		(pad "4" smd rect
			(at -1.778 1.299972 270)
			(size 1.016 0.381)
			(layers "B.Cu" "B.Mask" "B.Paste")
			(net "SPA_MID_DBG2_RX_BUF")
		)
		(pad "5" smd rect
			(at -1.778 0 270)
			(size 1.016 0.381)
			(layers "B.Cu" "B.Mask" "B.Paste")
			(net "P3V3_STBY")
		)
	)
	(footprint ""
		(layer "B.Cu")
		(at 350.9772 -88.269572 90)
		(property "Reference" "R3N31"
			(at 0 0 90)
			(layer "B.SilkS")
			(hide yes)
			(effects
				(font
					(size 1.27 1.27)
				)
				(justify mirror)
			)
		)
		(property "Value" ""
			(at 0 0 90)
			(layer "B.Fab")
			(effects
				(font
					(size 1.27 1.27)
				)
				(justify mirror)
			)
		)
		(duplicate_pad_numbers_are_jumpers no)
		(fp_poly
			(pts
				(xy 0.2794 -0.1016) (xy -0.2794 -0.1016) (xy -0.2794 0.9906) (xy 0.2794 0.9906)
			)
			(stroke
				(width 0)
				(type default)
			)
			(fill no)
			(layer "B.CrtYd")
		)
		(fp_line
			(start 0.2794 -0.1016)
			(end 0.2794 0.9906)
			(stroke
				(width 0.1)
				(type default)
			)
			(layer "B.Fab")
		)
		(fp_line
			(start -0.2794 -0.1016)
			(end 0.2794 -0.1016)
			(stroke
				(width 0.1)
				(type default)
			)
			(layer "B.Fab")
		)
		(fp_line
			(start 0.2794 0.9906)
			(end -0.2794 0.9906)
			(stroke
				(width 0.1)
				(type default)
			)
			(layer "B.Fab")
		)
		(fp_line
			(start -0.2794 0.9906)
			(end -0.2794 -0.1016)
			(stroke
				(width 0.1)
				(type default)
			)
			(layer "B.Fab")
		)
		(pad "1" smd rect
			(at 0 0 270)
			(size 0.508 0.508)
			(layers "B.Cu" "B.Mask" "B.Paste")
			(net "VR_PVCCIO_CPU0_XADDR1")
		)
		(pad "2" smd rect
			(at 0 0.889 270)
			(size 0.508 0.508)
			(layers "B.Cu" "B.Mask" "B.Paste")
			(net "GND")
		)
		(zone
			(layer "B.Cu")
			(hatch none 0.5)
			(connect_pads
				(clearance 0)
			)
			(min_thickness 0.25)
			(keepout
				(tracks allowed)
				(vias not_allowed)
				(pads allowed)
				(copperpour not_allowed)
				(footprints allowed)
			)
			(placement
				(enabled no)
				(sheetname "")
			)
			(fill
				(thermal_gap 0.5)
				(thermal_bridge_width 0.5)
				(island_removal_mode 0)
			)
			(polygon
				(pts
					(xy 351.2312 -88.523572) (xy 351.2312 -88.015572) (xy 351.6122 -88.015572) (xy 351.6122 -88.523572)
				)
			)
		)
		(zone
			(layer "B.Cu")
			(hatch none 0.5)
			(connect_pads
				(clearance 0)
			)
			(min_thickness 0.25)
			(keepout
				(tracks not_allowed)
				(vias allowed)
				(pads allowed)
				(copperpour not_allowed)
				(footprints allowed)
			)
			(placement
				(enabled no)
				(sheetname "")
			)
			(fill
				(thermal_gap 0.5)
				(thermal_bridge_width 0.5)
				(island_removal_mode 0)
			)
			(polygon
				(pts
					(xy 351.6122 -88.523572) (xy 351.6122 -88.015572) (xy 351.2312 -88.015572) (xy 351.2312 -88.523572)
				)
			)
		)
	)
)
